(kicad_pcb
	(version 20241229)
	(generator "pcbnew")
	(generator_version "9.0")
	(general
		(thickness 1.599998)
		(legacy_teardrops no)
	)
	(paper "A4")
	(title_block
		(title "Artix - Datacenter Secure Control Module (DC-SCM)")
		(date "2024-11-06")
		(rev "1.1.3")
		(comment 9 "footprints 203-207 of 544")
	)
	(layers
		(0 "F.Cu" signal)
		(4 "In1.Cu" signal)
		(6 "In2.Cu" signal)
		(8 "In3.Cu" signal)
		(10 "In4.Cu" signal)
		(12 "In5.Cu" signal)
		(14 "In6.Cu" signal)
		(2 "B.Cu" signal)
		(9 "F.Adhes" user "F.Adhesive")
		(11 "B.Adhes" user "B.Adhesive")
		(13 "F.Paste" user)
		(15 "B.Paste" user)
		(5 "F.SilkS" user "F.Silkscreen")
		(7 "B.SilkS" user "B.Silkscreen")
		(1 "F.Mask" user)
		(3 "B.Mask" user)
		(17 "Dwgs.User" user "User.Drawings")
		(19 "Cmts.User" user "User.Comments")
		(21 "Eco1.User" user "User.Eco1")
		(23 "Eco2.User" user "User.Eco2")
		(25 "Edge.Cuts" user)
		(27 "Margin" user)
		(31 "F.CrtYd" user "F.Courtyard")
		(29 "B.CrtYd" user "B.Courtyard")
		(35 "F.Fab" user)
		(33 "B.Fab" user)
	)
	(footprint "antmicro-footprints:C_0603_1608Metric"
		(layer "F.Cu")
		(at 84.59 63.79 180)
		(descr "Capacitor SMD 0603")
		(tags "capacitor 0603")
		(property "Reference" "C65"
			(at -7.31 -5.81 0)
			(layer "F.SilkS")
			(effects
				(font
					(size 0.7 0.7)
					(thickness 0.15)
				)
				(justify right bottom)
			)
		)
		(property "Value" "C_2u2_0603_25V"
			(at 0 1.6 0)
			(layer "F.Fab")
			(effects
				(font
					(size 0.7 0.7)
					(thickness 0.15)
				)
				(justify right bottom)
			)
		)
		(property "Datasheet" "https://www.murata.com/products/productdetail?partno=GRM188R61E225KA12%23"
			(at 0 0 180)
			(layer "F.Fab")
			(hide yes)
			(effects
				(font
					(size 1.27 1.27)
					(thickness 0.15)
				)
			)
		)
		(property "Description" "SMD Multilayer Ceramic Capacitor, 2.2 µF, 25 V, 0603 [1608 Metric], ± 10%, X5R, GRM Series"
			(at 0 0 180)
			(layer "F.Fab")
			(hide yes)
			(effects
				(font
					(size 1.27 1.27)
					(thickness 0.15)
				)
			)
		)
		(property "Author" "Antmicro"
			(at 169.18 127.58 0)
			(layer "F.Fab")
			(hide yes)
			(effects
				(font
					(size 1 1)
					(thickness 0.15)
				)
			)
		)
		(property "Dielectric" ""
			(at 169.18 127.58 0)
			(layer "F.Fab")
			(hide yes)
			(effects
				(font
					(size 1 1)
					(thickness 0.15)
				)
			)
		)
		(property "License" "Apache-2.0"
			(at 169.18 127.58 0)
			(layer "F.Fab")
			(hide yes)
			(effects
				(font
					(size 1 1)
					(thickness 0.15)
				)
			)
		)
		(property "MPN" "GRM188R61E225KA12D"
			(at 169.18 127.58 0)
			(layer "F.Fab")
			(hide yes)
			(effects
				(font
					(size 1 1)
					(thickness 0.15)
				)
			)
		)
		(property "Manufacturer" "Murata"
			(at 169.18 127.58 0)
			(layer "F.Fab")
			(hide yes)
			(effects
				(font
					(size 1 1)
					(thickness 0.15)
				)
			)
		)
		(property "Public" "False"
			(at 169.18 127.58 0)
			(layer "F.Fab")
			(hide yes)
			(effects
				(font
					(size 1 1)
					(thickness 0.15)
				)
			)
		)
		(property "Val" "2u2"
			(at 169.18 127.58 0)
			(layer "F.Fab")
			(hide yes)
			(effects
				(font
					(size 1 1)
					(thickness 0.15)
				)
			)
		)
		(property "Voltage" ""
			(at 169.18 127.58 0)
			(layer "F.Fab")
			(hide yes)
			(effects
				(font
					(size 1 1)
					(thickness 0.15)
				)
			)
		)
		(sheetname "/Power supply/")
		(sheetfile "power-supply.kicad_sch")
		(attr smd)
		(fp_line
			(start -0.15 0.4)
			(end 0.15 0.4)
			(stroke
				(width 0.15)
				(type solid)
			)
			(layer "F.SilkS")
		)
		(fp_line
			(start -0.15 -0.4)
			(end 0.15 -0.4)
			(stroke
				(width 0.15)
				(type solid)
			)
			(layer "F.SilkS")
		)
		(fp_rect
			(start -1.25 -0.65)
			(end 1.25 0.65)
			(stroke
				(width 0.05)
				(type solid)
			)
			(fill no)
			(layer "F.CrtYd")
		)
		(fp_rect
			(start -0.8 -0.4)
			(end 0.8 0.4)
			(stroke
				(width 0.15)
				(type solid)
			)
			(fill no)
			(layer "F.Fab")
		)
		(pad "1" smd roundrect
			(at -0.7 0 180)
			(size 0.8 1)
			(layers "F.Cu" "F.Mask" "F.Paste")
			(roundrect_rratio 0.2)
			(net 1 "GND")
			(pintype "passive")
		)
		(pad "2" smd roundrect
			(at 0.7 0 180)
			(size 0.8 1)
			(layers "F.Cu" "F.Mask" "F.Paste")
			(roundrect_rratio 0.2)
			(net 104 "/Power supply/VCC12V")
			(pintype "passive")
		)
	)
	(footprint "antmicro-footprints:C_0603_1608Metric"
		(layer "F.Cu")
		(at 85.265 68.765 -90)
		(descr "Capacitor SMD 0603")
		(tags "capacitor 0603")
		(property "Reference" "C14"
			(at -1.115 0.795 90)
			(layer "F.SilkS")
			(effects
				(font
					(size 0.7 0.7)
					(thickness 0.15)
				)
				(justify right bottom)
			)
		)
		(property "Value" "C_10u_25V_0603"
			(at 0 1.6 90)
			(layer "F.Fab")
			(effects
				(font
					(size 0.7 0.7)
					(thickness 0.15)
				)
				(justify right bottom)
			)
		)
		(property "Datasheet" "https://product.tdk.com/en/search/capacitor/ceramic/mlcc/info?part_no=C1608X5R1E106M080AC"
			(at 0 0 270)
			(layer "F.Fab")
			(hide yes)
			(effects
				(font
					(size 1.27 1.27)
					(thickness 0.15)
				)
			)
		)
		(property "Description" "SMD Multilayer Ceramic Capacitor, 10 µF, 25 V, 0603 [1608 Metric], ± 20%, X5R, C"
			(at 0 0 270)
			(layer "F.Fab")
			(hide yes)
			(effects
				(font
					(size 1.27 1.27)
					(thickness 0.15)
				)
			)
		)
		(property "Author" "Antmicro"
			(at 16.5 154.03 0)
			(layer "F.Fab")
			(hide yes)
			(effects
				(font
					(size 1 1)
					(thickness 0.15)
				)
			)
		)
		(property "Dielectric" ""
			(at 16.5 154.03 0)
			(layer "F.Fab")
			(hide yes)
			(effects
				(font
					(size 1 1)
					(thickness 0.15)
				)
			)
		)
		(property "License" "Apache-2.0"
			(at 16.5 154.03 0)
			(layer "F.Fab")
			(hide yes)
			(effects
				(font
					(size 1 1)
					(thickness 0.15)
				)
			)
		)
		(property "MPN" "C1608X5R1E106M080AC"
			(at 16.5 154.03 0)
			(layer "F.Fab")
			(hide yes)
			(effects
				(font
					(size 1 1)
					(thickness 0.15)
				)
			)
		)
		(property "Manufacturer" "TDK"
			(at 16.5 154.03 0)
			(layer "F.Fab")
			(hide yes)
			(effects
				(font
					(size 1 1)
					(thickness 0.15)
				)
			)
		)
		(property "Val" "10u"
			(at 16.5 154.03 0)
			(layer "F.Fab")
			(hide yes)
			(effects
				(font
					(size 1 1)
					(thickness 0.15)
				)
			)
		)
		(property "Voltage" "25V"
			(at 16.5 154.03 0)
			(layer "F.Fab")
			(hide yes)
			(effects
				(font
					(size 1 1)
					(thickness 0.15)
				)
			)
		)
		(sheetname "/Power supply/")
		(sheetfile "power-supply.kicad_sch")
		(attr smd)
		(fp_line
			(start -0.15 0.4)
			(end 0.15 0.4)
			(stroke
				(width 0.15)
				(type solid)
			)
			(layer "F.SilkS")
		)
		(fp_line
			(start -0.15 -0.4)
			(end 0.15 -0.4)
			(stroke
				(width 0.15)
				(type solid)
			)
			(layer "F.SilkS")
		)
		(fp_rect
			(start -1.25 -0.65)
			(end 1.25 0.65)
			(stroke
				(width 0.05)
				(type solid)
			)
			(fill no)
			(layer "F.CrtYd")
		)
		(fp_rect
			(start -0.8 -0.4)
			(end 0.8 0.4)
			(stroke
				(width 0.15)
				(type solid)
			)
			(fill no)
			(layer "F.Fab")
		)
		(pad "1" smd roundrect
			(at -0.7 0 270)
			(size 0.8 1)
			(layers "F.Cu" "F.Mask" "F.Paste")
			(roundrect_rratio 0.2)
			(net 1 "GND")
			(pintype "passive")
		)
		(pad "2" smd roundrect
			(at 0.7 0 270)
			(size 0.8 1)
			(layers "F.Cu" "F.Mask" "F.Paste")
			(roundrect_rratio 0.2)
			(net 104 "/Power supply/VCC12V")
			(pintype "passive")
		)
	)
	(footprint "antmicro-footprints:C_0603_1608Metric"
		(layer "F.Cu")
		(at 88.215 68.765 -90)
		(descr "Capacitor SMD 0603")
		(tags "capacitor 0603")
		(property "Reference" "C15"
			(at -3.365 -0.185 90)
			(layer "F.SilkS")
			(effects
				(font
					(size 0.7 0.7)
					(thickness 0.15)
				)
				(justify right bottom)
			)
		)
		(property "Value" "C_10u_25V_0603"
			(at 0 1.6 90)
			(layer "F.Fab")
			(effects
				(font
					(size 0.7 0.7)
					(thickness 0.15)
				)
				(justify right bottom)
			)
		)
		(property "Datasheet" "https://product.tdk.com/en/search/capacitor/ceramic/mlcc/info?part_no=C1608X5R1E106M080AC"
			(at 0 0 270)
			(layer "F.Fab")
			(hide yes)
			(effects
				(font
					(size 1.27 1.27)
					(thickness 0.15)
				)
			)
		)
		(property "Description" "SMD Multilayer Ceramic Capacitor, 10 µF, 25 V, 0603 [1608 Metric], ± 20%, X5R, C"
			(at 0 0 270)
			(layer "F.Fab")
			(hide yes)
			(effects
				(font
					(size 1.27 1.27)
					(thickness 0.15)
				)
			)
		)
		(property "Author" "Antmicro"
			(at 19.45 156.98 0)
			(layer "F.Fab")
			(hide yes)
			(effects
				(font
					(size 1 1)
					(thickness 0.15)
				)
			)
		)
		(property "Dielectric" ""
			(at 19.45 156.98 0)
			(layer "F.Fab")
			(hide yes)
			(effects
				(font
					(size 1 1)
					(thickness 0.15)
				)
			)
		)
		(property "License" "Apache-2.0"
			(at 19.45 156.98 0)
			(layer "F.Fab")
			(hide yes)
			(effects
				(font
					(size 1 1)
					(thickness 0.15)
				)
			)
		)
		(property "MPN" "C1608X5R1E106M080AC"
			(at 19.45 156.98 0)
			(layer "F.Fab")
			(hide yes)
			(effects
				(font
					(size 1 1)
					(thickness 0.15)
				)
			)
		)
		(property "Manufacturer" "TDK"
			(at 19.45 156.98 0)
			(layer "F.Fab")
			(hide yes)
			(effects
				(font
					(size 1 1)
					(thickness 0.15)
				)
			)
		)
		(property "Val" "10u"
			(at 19.45 156.98 0)
			(layer "F.Fab")
			(hide yes)
			(effects
				(font
					(size 1 1)
					(thickness 0.15)
				)
			)
		)
		(property "Voltage" "25V"
			(at 19.45 156.98 0)
			(layer "F.Fab")
			(hide yes)
			(effects
				(font
					(size 1 1)
					(thickness 0.15)
				)
			)
		)
		(sheetname "/Power supply/")
		(sheetfile "power-supply.kicad_sch")
		(attr smd)
		(fp_line
			(start -0.15 0.4)
			(end 0.15 0.4)
			(stroke
				(width 0.15)
				(type solid)
			)
			(layer "F.SilkS")
		)
		(fp_line
			(start -0.15 -0.4)
			(end 0.15 -0.4)
			(stroke
				(width 0.15)
				(type solid)
			)
			(layer "F.SilkS")
		)
		(fp_rect
			(start -1.25 -0.65)
			(end 1.25 0.65)
			(stroke
				(width 0.05)
				(type solid)
			)
			(fill no)
			(layer "F.CrtYd")
		)
		(fp_rect
			(start -0.8 -0.4)
			(end 0.8 0.4)
			(stroke
				(width 0.15)
				(type solid)
			)
			(fill no)
			(layer "F.Fab")
		)
		(pad "1" smd roundrect
			(at -0.7 0 270)
			(size 0.8 1)
			(layers "F.Cu" "F.Mask" "F.Paste")
			(roundrect_rratio 0.2)
			(net 1 "GND")
			(pintype "passive")
		)
		(pad "2" smd roundrect
			(at 0.7 0 270)
			(size 0.8 1)
			(layers "F.Cu" "F.Mask" "F.Paste")
			(roundrect_rratio 0.2)
			(net 104 "/Power supply/VCC12V")
			(pintype "passive")
		)
	)
	(footprint "antmicro-footprints:C_0603_1608Metric"
		(layer "F.Cu")
		(at 86.74 68.765 -90)
		(descr "Capacitor SMD 0603")
		(tags "capacitor 0603")
		(property "Reference" "C16"
			(at -3.355 -0.4735 90)
			(layer "F.SilkS")
			(effects
				(font
					(size 0.7 0.7)
					(thickness 0.15)
				)
				(justify right bottom)
			)
		)
		(property "Value" "C_10u_25V_0603"
			(at 0 1.6 90)
			(layer "F.Fab")
			(effects
				(font
					(size 0.7 0.7)
					(thickness 0.15)
				)
				(justify right bottom)
			)
		)
		(property "Datasheet" "https://product.tdk.com/en/search/capacitor/ceramic/mlcc/info?part_no=C1608X5R1E106M080AC"
			(at 0 0 270)
			(layer "F.Fab")
			(hide yes)
			(effects
				(font
					(size 1.27 1.27)
					(thickness 0.15)
				)
			)
		)
		(property "Description" "SMD Multilayer Ceramic Capacitor, 10 µF, 25 V, 0603 [1608 Metric], ± 20%, X5R, C"
			(at 0 0 270)
			(layer "F.Fab")
			(hide yes)
			(effects
				(font
					(size 1.27 1.27)
					(thickness 0.15)
				)
			)
		)
		(property "Author" "Antmicro"
			(at 17.975 155.505 0)
			(layer "F.Fab")
			(hide yes)
			(effects
				(font
					(size 1 1)
					(thickness 0.15)
				)
			)
		)
		(property "Dielectric" ""
			(at 17.975 155.505 0)
			(layer "F.Fab")
			(hide yes)
			(effects
				(font
					(size 1 1)
					(thickness 0.15)
				)
			)
		)
		(property "License" "Apache-2.0"
			(at 17.975 155.505 0)
			(layer "F.Fab")
			(hide yes)
			(effects
				(font
					(size 1 1)
					(thickness 0.15)
				)
			)
		)
		(property "MPN" "C1608X5R1E106M080AC"
			(at 17.975 155.505 0)
			(layer "F.Fab")
			(hide yes)
			(effects
				(font
					(size 1 1)
					(thickness 0.15)
				)
			)
		)
		(property "Manufacturer" "TDK"
			(at 17.975 155.505 0)
			(layer "F.Fab")
			(hide yes)
			(effects
				(font
					(size 1 1)
					(thickness 0.15)
				)
			)
		)
		(property "Val" "10u"
			(at 17.975 155.505 0)
			(layer "F.Fab")
			(hide yes)
			(effects
				(font
					(size 1 1)
					(thickness 0.15)
				)
			)
		)
		(property "Voltage" "25V"
			(at 17.975 155.505 0)
			(layer "F.Fab")
			(hide yes)
			(effects
				(font
					(size 1 1)
					(thickness 0.15)
				)
			)
		)
		(sheetname "/Power supply/")
		(sheetfile "power-supply.kicad_sch")
		(attr smd)
		(fp_line
			(start -0.15 0.4)
			(end 0.15 0.4)
			(stroke
				(width 0.15)
				(type solid)
			)
			(layer "F.SilkS")
		)
		(fp_line
			(start -0.15 -0.4)
			(end 0.15 -0.4)
			(stroke
				(width 0.15)
				(type solid)
			)
			(layer "F.SilkS")
		)
		(fp_rect
			(start -1.25 -0.65)
			(end 1.25 0.65)
			(stroke
				(width 0.05)
				(type solid)
			)
			(fill no)
			(layer "F.CrtYd")
		)
		(fp_rect
			(start -0.8 -0.4)
			(end 0.8 0.4)
			(stroke
				(width 0.15)
				(type solid)
			)
			(fill no)
			(layer "F.Fab")
		)
		(pad "1" smd roundrect
			(at -0.7 0 270)
			(size 0.8 1)
			(layers "F.Cu" "F.Mask" "F.Paste")
			(roundrect_rratio 0.2)
			(net 1 "GND")
			(pintype "passive")
		)
		(pad "2" smd roundrect
			(at 0.7 0 270)
			(size 0.8 1)
			(layers "F.Cu" "F.Mask" "F.Paste")
			(roundrect_rratio 0.2)
			(net 104 "/Power supply/VCC12V")
			(pintype "passive")
		)
	)
	(footprint "antmicro-footprints:Conn_Molex_Pico-Lock_1x2_504050-0291"
		(layer "F.Cu")
		(at 89.6 62.55 180)
		(property "Reference" "J5"
			(at 5.55 2.55 180)
			(layer "F.SilkS")
			(effects
				(font
					(size 0.7 0.7)
					(thickness 0.15)
				)
				(justify left bottom)
			)
		)
		(property "Value" "Molex_Pico-Lock_1x2_504050-0291"
			(at -0.749 4.35 180)
			(layer "F.Fab")
			(effects
				(font
					(size 0.7 0.7)
					(thickness 0.15)
				)
				(justify left bottom)
			)
		)
		(property "Datasheet" "https://www.molex.com/en-us/products/part-detail-pdf/5040500291?display=pdf"
			(at 0 0 180)
			(layer "F.Fab")
			(hide yes)
			(effects
				(font
					(size 1.27 1.27)
					(thickness 0.15)
				)
			)
		)
		(property "Description" "Connector Header Surface Mount, Right Angle 2 position 0.059\" (1.50mm)"
			(at 0 0 180)
			(layer "F.Fab")
			(hide yes)
			(effects
				(font
					(size 1.27 1.27)
					(thickness 0.15)
				)
			)
		)
		(property "Author" "Antmicro"
			(at 179.2 125.1 0)
			(layer "F.Fab")
			(hide yes)
			(effects
				(font
					(size 1 1)
					(thickness 0.15)
				)
			)
		)
		(property "License" "Apache-2.0"
			(at 179.2 125.1 0)
			(layer "F.Fab")
			(hide yes)
			(effects
				(font
					(size 1 1)
					(thickness 0.15)
				)
			)
		)
		(property "MPN" "504050-0291"
			(at 179.2 125.1 0)
			(layer "F.Fab")
			(hide yes)
			(effects
				(font
					(size 1 1)
					(thickness 0.15)
				)
			)
		)
		(property "Manufacturer" "Molex"
			(at 179.2 125.1 0)
			(layer "F.Fab")
			(hide yes)
			(effects
				(font
					(size 1 1)
					(thickness 0.15)
				)
			)
		)
		(sheetname "/Power supply/")
		(sheetfile "power-supply.kicad_sch")
		(attr smd)
		(fp_line
			(start 3.374 -2.86)
			(end 3.374 1.088)
			(stroke
				(width 0.15)
				(type solid)
			)
			(layer "F.SilkS")
		)
		(fp_line
			(start 1.649 1.289)
			(end 1.649 3.228)
			(stroke
				(width 0.15)
				(type solid)
			)
			(layer "F.SilkS")
		)
		(fp_line
			(start 1.649 1.289)
			(end -1.639 1.289)
			(stroke
				(width 0.15)
				(type solid)
			)
			(layer "F.SilkS")
		)
		(fp_line
			(start 1.399 -2.86)
			(end 3.374 -2.86)
			(stroke
				(width 0.15)
				(type solid)
			)
			(layer "F.SilkS")
		)
		(fp_line
			(start -1.639 3.239)
			(end -1.639 1.289)
			(stroke
				(width 0.15)
				(type solid)
			)
			(layer "F.SilkS")
		)
		(fp_line
			(start -3.374 1.088)
			(end -3.374 -2.86)
			(stroke
				(width 0.15)
				(type solid)
			)
			(layer "F.SilkS")
		)
		(fp_line
			(start -3.374 -2.86)
			(end -1.4 -2.86)
			(stroke
				(width 0.15)
				(type solid)
			)
			(layer "F.SilkS")
		)
		(fp_circle
			(center -1.249 -3.15)
			(end -1.199 -3.15)
			(stroke
				(width 0.15)
				(type solid)
			)
			(fill yes)
			(layer "F.SilkS")
		)
		(fp_line
			(start 4.231 3.47)
			(end -4.249 3.47)
			(stroke
				(width 0.05)
				(type solid)
			)
			(layer "F.CrtYd")
		)
		(fp_line
			(start 4.231 1.18)
			(end 4.231 3.47)
			(stroke
				(width 0.05)
				(type solid)
			)
			(layer "F.CrtYd")
		)
		(fp_line
			(start 3.621 1.18)
			(end 4.231 1.18)
			(stroke
				(width 0.05)
				(type solid)
			)
			(layer "F.CrtYd")
		)
		(fp_line
			(start 3.621 -3.61)
			(end 3.621 1.18)
			(stroke
				(width 0.05)
				(type solid)
			)
			(layer "F.CrtYd")
		)
		(fp_line
			(start -3.629 1.18)
			(end -3.629 -3.61)
			(stroke
				(width 0.05)
				(type solid)
			)
			(layer "F.CrtYd")
		)
		(fp_line
			(start -3.629 -3.61)
			(end 3.621 -3.61)
			(stroke
				(width 0.05)
				(type solid)
			)
			(layer "F.CrtYd")
		)
		(fp_line
			(start -4.249 3.47)
			(end -4.249 1.18)
			(stroke
				(width 0.05)
				(type solid)
			)
			(layer "F.CrtYd")
		)
		(fp_line
			(start -4.249 1.18)
			(end -3.629 1.18)
			(stroke
				(width 0.05)
				(type solid)
			)
			(layer "F.CrtYd")
		)
		(fp_line
			(start 3.374 -2.86)
			(end 3.374 3.239)
			(stroke
				(width 0.15)
				(type solid)
			)
			(layer "F.Fab")
		)
		(fp_line
			(start 1.75 3.239)
			(end 3.374 3.239)
			(stroke
				(width 0.15)
				(type solid)
			)
			(layer "F.Fab")
		)
		(fp_line
			(start 1.75 1.188)
			(end 1.75 3.239)
			(stroke
				(width 0.15)
				(type solid)
			)
			(layer "F.Fab")
		)
		(fp_line
			(start 1.75 1.188)
			(end -1.749 1.188)
			(stroke
				(width 0.15)
				(type solid)
			)
			(layer "F.Fab")
		)
		(fp_line
			(start -1.749 3.249)
			(end -1.749 1.188)
			(stroke
				(width 0.15)
				(type solid)
			)
			(layer "F.Fab")
		)
		(fp_line
			(start -3.374 3.239)
			(end -1.749 3.239)
			(stroke
				(width 0.15)
				(type solid)
			)
			(layer "F.Fab")
		)
		(fp_line
			(start -3.374 3.239)
			(end -3.374 -2.86)
			(stroke
				(width 0.15)
				(type solid)
			)
			(layer "F.Fab")
		)
		(fp_line
			(start -3.374 -2.86)
			(end 3.374 -2.86)
			(stroke
				(width 0.15)
				(type solid)
			)
			(layer "F.Fab")
		)
		(fp_text user "${REFERENCE}"
			(at -3.481 10.175 180)
			(layer "F.Fab")
			(effects
				(font
					(size 0.7 0.7)
					(thickness 0.15)
				)
				(justify left bottom)
			)
		)
		(fp_text user "Author: Antmicro"
			(at -3.481 11.374 180)
			(layer "F.Fab")
			(effects
				(font
					(size 0.7 0.7)
					(thickness 0.15)
				)
				(justify left bottom)
			)
		)
		(fp_text user "License: Apache-2.0"
			(at -3.481 12.573 180)
			(layer "F.Fab")
			(effects
				(font
					(size 0.7 0.7)
					(thickness 0.15)
				)
				(justify left bottom)
			)
		)
		(pad "1" smd roundrect
			(at -0.749 -2.85 180)
			(size 0.6 1)
			(layers "F.Cu" "F.Mask" "F.Paste")
			(roundrect_rratio 0.25)
			(net 104 "/Power supply/VCC12V")
			(pinfunction "1")
			(pintype "passive")
		)
		(pad "2" smd roundrect
			(at 0.75 -2.85 180)
			(size 0.6 1)
			(layers "F.Cu" "F.Mask" "F.Paste")
			(roundrect_rratio 0.25)
			(net 1 "GND")
			(pinfunction "2")
			(pintype "passive")
		)
		(pad "MP1" smd roundrect
			(at -3.354 2.338 180)
			(size 1.25 1.8)
			(layers "F.Cu" "F.Mask" "F.Paste")
			(roundrect_rratio 0.25)
			(net 1 "GND")
			(pinfunction "MP")
			(pintype "passive")
		)
		(pad "MP2" smd roundrect
			(at 3.356 2.338 180)
			(size 1.25 1.8)
			(layers "F.Cu" "F.Mask" "F.Paste")
			(roundrect_rratio 0.25)
			(net 1 "GND")
			(pinfunction "MP2")
			(pintype "passive")
		)
	)
)
